(kicad_pcb
	(version 20260206)
	(generator "pcbnew")
	(generator_version "10.0")
	(general
		(thickness 1.6)
		(legacy_teardrops no)
	)
	(paper "A4")
	(title_block
		(title "9054_F0T_PDB_BD_GPU_F_V04_1213_1550_OCP.brd")
		(comment 1 "Grand Teton / footprint 313 of 608 (J4), pads 1-38 of 38")
	)
	(layers
		(0 "F.Cu" signal "TOP")
		(4 "In1.Cu" signal "GND")
		(6 "In2.Cu" signal "IN1")
		(8 "In3.Cu" signal "GND1")
		(10 "In4.Cu" signal "VCC")
		(12 "In5.Cu" signal "VCC1")
		(14 "In6.Cu" signal "GND2")
		(16 "In7.Cu" signal "IN2")
		(18 "In8.Cu" signal "GND3")
		(2 "B.Cu" signal "BOTTOM")
		(9 "F.Adhes" user "F.Adhesive")
		(11 "B.Adhes" user "B.Adhesive")
		(13 "F.Paste" user "Package Geometry/Pastemask Top")
		(15 "B.Paste" user "Package Geometry/Pastemask Bottom")
		(5 "F.SilkS" user "Ref Des/Silkscreen Top")
		(7 "B.SilkS" user "Ref Des/Silkscreen Bottom")
		(1 "F.Mask" user "Board Geometry/Soldermask Top")
		(3 "B.Mask" user "Board Geometry/Soldermask Bottom")
		(17 "Dwgs.User" user "User.Drawings")
		(19 "Cmts.User" user "User.Comments")
		(21 "Eco1.User" user "User.Eco1")
		(23 "Eco2.User" user "User.Eco2")
		(25 "Edge.Cuts" user "Board Geometry/Outline")
		(27 "Margin" user)
		(31 "F.CrtYd" user "Package Geometry/Place Bound Top")
		(29 "B.CrtYd" user "Package Geometry/Place Bound Bottom")
		(35 "F.Fab" user "Ref Des/Assembly Top")
		(33 "B.Fab" user "Ref Des/Assembly Bottom")
	)
	(footprint ""
		(layer "F.Cu")
		(at 77.0001 -156.830014 180)
		(property "Reference" "J4"
			(at 3.7211 -10.603484 0)
			(unlocked yes)
			(layer "F.SilkS")
			(effects
				(font
					(size 0.7874 0.5842)
					(thickness 0.1524)
				)
				(justify left)
			)
		)
		(property "Value" ""
			(at 0 0 180)
			(layer "F.Fab")
			(effects
				(font
					(size 1.27 1.27)
				)
			)
		)
		(duplicate_pad_numbers_are_jumpers no)
		(pad "" np_thru_hole circle
			(at 3.999992 2.800096 180)
			(size 2.159 2.159)
			(drill 2.159)
			(layers "*.Cu" "*.Mask")
			(clearance 0.381)
			(thermal_gap 0.381)
		)
		(pad "" np_thru_hole circle
			(at 9.99998 10.80008 180)
			(size 2.159 2.159)
			(drill 2.159)
			(layers "*.Cu" "*.Mask")
			(clearance 0.381)
			(thermal_gap 0.381)
		)
		(pad "A1" thru_hole rect
			(at 0 0 180)
			(size 1.156208 1.156208)
			(drill 0.749808)
			(layers "*.Cu" "*.Mask")
			(remove_unused_layers no)
			(net "P52V_HS2")
			(clearance 0.0508)
			(thermal_gap 0.0508)
			(padstack
				(mode front_inner_back)
				(layer "Inner"
					(shape circle)
					(size 1.156208 1.156208)
					(clearance 0.0508)
				)
				(layer "B.Cu"
					(shape rect)
					(size 1.156208 1.156208)
					(clearance 0.0508)
				)
			)
		)
		(pad "A2" thru_hole circle
			(at 0 1.999996 180)
			(size 1.156208 1.156208)
			(drill 0.749808)
			(layers "*.Cu" "*.Mask")
			(remove_unused_layers no)
			(net "P52V_HS2")
			(clearance 0.0508)
			(thermal_gap 0.0508)
		)
		(pad "A3" thru_hole circle
			(at 0 3.999992 180)
			(size 1.156208 1.156208)
			(drill 0.749808)
			(layers "*.Cu" "*.Mask")
			(remove_unused_layers no)
			(net "P52V_HS2")
			(clearance 0.0508)
			(thermal_gap 0.0508)
		)
		(pad "A4" thru_hole circle
			(at 1.999996 3.999992 180)
			(size 1.156208 1.156208)
			(drill 0.749808)
			(layers "*.Cu" "*.Mask")
			(remove_unused_layers no)
			(net "P52V_HS2")
			(clearance 0.0508)
			(thermal_gap 0.0508)
		)
		(pad "A5" thru_hole circle
			(at 1.999996 1.999996 180)
			(size 1.156208 1.156208)
			(drill 0.749808)
			(layers "*.Cu" "*.Mask")
			(remove_unused_layers no)
			(net "P52V_HS2")
			(clearance 0.0508)
			(thermal_gap 0.0508)
		)
		(pad "A6" thru_hole circle
			(at 1.999996 0 180)
			(size 1.156208 1.156208)
			(drill 0.749808)
			(layers "*.Cu" "*.Mask")
			(remove_unused_layers no)
			(net "P52V_HS2")
			(clearance 0.0508)
			(thermal_gap 0.0508)
		)
		(pad "B1" thru_hole circle
			(at 5.999988 0 180)
			(size 1.156208 1.156208)
			(drill 0.749808)
			(layers "*.Cu" "*.Mask")
			(remove_unused_layers no)
			(net "P52V_HS2")
			(clearance 0.0508)
			(thermal_gap 0.0508)
		)
		(pad "B2" thru_hole circle
			(at 5.999988 1.999996 180)
			(size 1.156208 1.156208)
			(drill 0.749808)
			(layers "*.Cu" "*.Mask")
			(remove_unused_layers no)
			(net "P52V_HS2")
			(clearance 0.0508)
			(thermal_gap 0.0508)
		)
		(pad "B3" thru_hole circle
			(at 5.999988 3.999992 180)
			(size 1.156208 1.156208)
			(drill 0.749808)
			(layers "*.Cu" "*.Mask")
			(remove_unused_layers no)
			(net "P52V_HS2")
			(clearance 0.0508)
			(thermal_gap 0.0508)
		)
		(pad "B4" thru_hole circle
			(at 7.999984 3.999992 180)
			(size 1.156208 1.156208)
			(drill 0.749808)
			(layers "*.Cu" "*.Mask")
			(remove_unused_layers no)
			(net "P52V_HS2")
			(clearance 0.0508)
			(thermal_gap 0.0508)
		)
		(pad "B5" thru_hole circle
			(at 7.999984 1.999996 180)
			(size 1.156208 1.156208)
			(drill 0.749808)
			(layers "*.Cu" "*.Mask")
			(remove_unused_layers no)
			(net "P52V_HS2")
			(clearance 0.0508)
			(thermal_gap 0.0508)
		)
		(pad "B6" thru_hole circle
			(at 7.999984 0 180)
			(size 1.156208 1.156208)
			(drill 0.749808)
			(layers "*.Cu" "*.Mask")
			(remove_unused_layers no)
			(net "P52V_HS2")
			(clearance 0.0508)
			(thermal_gap 0.0508)
		)
		(pad "C1" thru_hole circle
			(at 11.999976 0 180)
			(size 1.156208 1.156208)
			(drill 0.749808)
			(layers "*.Cu" "*.Mask")
			(remove_unused_layers no)
			(net "P52V_HS2")
			(clearance 0.0508)
			(thermal_gap 0.0508)
		)
		(pad "C2" thru_hole circle
			(at 11.999976 1.999996 180)
			(size 1.156208 1.156208)
			(drill 0.749808)
			(layers "*.Cu" "*.Mask")
			(remove_unused_layers no)
			(net "P52V_HS2")
			(clearance 0.0508)
			(thermal_gap 0.0508)
		)
		(pad "C3" thru_hole circle
			(at 11.999976 3.999992 180)
			(size 1.156208 1.156208)
			(drill 0.749808)
			(layers "*.Cu" "*.Mask")
			(remove_unused_layers no)
			(net "P52V_HS2")
			(clearance 0.0508)
			(thermal_gap 0.0508)
		)
		(pad "C4" thru_hole circle
			(at 13.999972 3.999992 180)
			(size 1.156208 1.156208)
			(drill 0.749808)
			(layers "*.Cu" "*.Mask")
			(remove_unused_layers no)
			(net "P52V_HS2")
			(clearance 0.0508)
			(thermal_gap 0.0508)
		)
		(pad "C5" thru_hole circle
			(at 13.999972 1.999996 180)
			(size 1.156208 1.156208)
			(drill 0.749808)
			(layers "*.Cu" "*.Mask")
			(remove_unused_layers no)
			(net "P52V_HS2")
			(clearance 0.0508)
			(thermal_gap 0.0508)
		)
		(pad "C6" thru_hole circle
			(at 13.999972 0 180)
			(size 1.156208 1.156208)
			(drill 0.749808)
			(layers "*.Cu" "*.Mask")
			(remove_unused_layers no)
			(net "P52V_HS2")
			(clearance 0.0508)
			(thermal_gap 0.0508)
		)
		(pad "D1" thru_hole circle
			(at 11.999976 7.999984 180)
			(size 1.156208 1.156208)
			(drill 0.749808)
			(layers "*.Cu" "*.Mask")
			(remove_unused_layers no)
			(net "GND")
			(clearance 0.0508)
			(thermal_gap 0.0508)
		)
		(pad "D2" thru_hole circle
			(at 11.999976 9.99998 180)
			(size 1.156208 1.156208)
			(drill 0.749808)
			(layers "*.Cu" "*.Mask")
			(remove_unused_layers no)
			(net "GND")
			(clearance 0.0508)
			(thermal_gap 0.0508)
		)
		(pad "D3" thru_hole circle
			(at 11.999976 11.999976 180)
			(size 1.156208 1.156208)
			(drill 0.749808)
			(layers "*.Cu" "*.Mask")
			(remove_unused_layers no)
			(net "GND")
			(clearance 0.0508)
			(thermal_gap 0.0508)
		)
		(pad "D4" thru_hole circle
			(at 13.999972 11.999976 180)
			(size 1.156208 1.156208)
			(drill 0.749808)
			(layers "*.Cu" "*.Mask")
			(remove_unused_layers no)
			(net "GND")
			(clearance 0.0508)
			(thermal_gap 0.0508)
		)
		(pad "D5" thru_hole circle
			(at 13.999972 9.99998 180)
			(size 1.156208 1.156208)
			(drill 0.749808)
			(layers "*.Cu" "*.Mask")
			(remove_unused_layers no)
			(net "GND")
			(clearance 0.0508)
			(thermal_gap 0.0508)
		)
		(pad "D6" thru_hole circle
			(at 13.999972 7.999984 180)
			(size 1.156208 1.156208)
			(drill 0.749808)
			(layers "*.Cu" "*.Mask")
			(remove_unused_layers no)
			(net "GND")
			(clearance 0.0508)
			(thermal_gap 0.0508)
		)
		(pad "E1" thru_hole circle
			(at 5.999988 7.999984 180)
			(size 1.156208 1.156208)
			(drill 0.749808)
			(layers "*.Cu" "*.Mask")
			(remove_unused_layers no)
			(net "GND")
			(clearance 0.0508)
			(thermal_gap 0.0508)
		)
		(pad "E2" thru_hole circle
			(at 5.999988 9.99998 180)
			(size 1.156208 1.156208)
			(drill 0.749808)
			(layers "*.Cu" "*.Mask")
			(remove_unused_layers no)
			(net "GND")
			(clearance 0.0508)
			(thermal_gap 0.0508)
		)
		(pad "E3" thru_hole circle
			(at 5.999988 11.999976 180)
			(size 1.156208 1.156208)
			(drill 0.749808)
			(layers "*.Cu" "*.Mask")
			(remove_unused_layers no)
			(net "GND")
			(clearance 0.0508)
			(thermal_gap 0.0508)
		)
		(pad "E4" thru_hole circle
			(at 7.999984 11.999976 180)
			(size 1.156208 1.156208)
			(drill 0.749808)
			(layers "*.Cu" "*.Mask")
			(remove_unused_layers no)
			(net "GND")
			(clearance 0.0508)
			(thermal_gap 0.0508)
		)
		(pad "E5" thru_hole circle
			(at 7.999984 9.99998 180)
			(size 1.156208 1.156208)
			(drill 0.749808)
			(layers "*.Cu" "*.Mask")
			(remove_unused_layers no)
			(net "GND")
			(clearance 0.0508)
			(thermal_gap 0.0508)
		)
		(pad "E6" thru_hole circle
			(at 7.999984 7.999984 180)
			(size 1.156208 1.156208)
			(drill 0.749808)
			(layers "*.Cu" "*.Mask")
			(remove_unused_layers no)
			(net "GND")
			(clearance 0.0508)
			(thermal_gap 0.0508)
		)
		(pad "F1" thru_hole circle
			(at 0 7.999984 180)
			(size 1.156208 1.156208)
			(drill 0.749808)
			(layers "*.Cu" "*.Mask")
			(remove_unused_layers no)
			(net "GND")
			(clearance 0.0508)
			(thermal_gap 0.0508)
		)
		(pad "F2" thru_hole circle
			(at 0 9.99998 180)
			(size 1.156208 1.156208)
			(drill 0.749808)
			(layers "*.Cu" "*.Mask")
			(remove_unused_layers no)
			(net "GND")
			(clearance 0.0508)
			(thermal_gap 0.0508)
		)
		(pad "F3" thru_hole circle
			(at 0 11.999976 180)
			(size 1.156208 1.156208)
			(drill 0.749808)
			(layers "*.Cu" "*.Mask")
			(remove_unused_layers no)
			(net "GND")
			(clearance 0.0508)
			(thermal_gap 0.0508)
		)
		(pad "F4" thru_hole circle
			(at 1.999996 11.999976 180)
			(size 1.156208 1.156208)
			(drill 0.749808)
			(layers "*.Cu" "*.Mask")
			(remove_unused_layers no)
			(net "GND")
			(clearance 0.0508)
			(thermal_gap 0.0508)
		)
		(pad "F5" thru_hole circle
			(at 1.999996 9.99998 180)
			(size 1.156208 1.156208)
			(drill 0.749808)
			(layers "*.Cu" "*.Mask")
			(remove_unused_layers no)
			(net "GND")
			(clearance 0.0508)
			(thermal_gap 0.0508)
		)
		(pad "F6" thru_hole circle
			(at 1.999996 7.999984 180)
			(size 1.156208 1.156208)
			(drill 0.749808)
			(layers "*.Cu" "*.Mask")
			(remove_unused_layers no)
			(net "GND")
			(clearance 0.0508)
			(thermal_gap 0.0508)
		)
	)
)
